(kicad_pcb
	(version 20260206)
	(generator "pcbnew")
	(generator_version "10.0")
	(general
		(thickness 1.6)
		(legacy_teardrops no)
	)
	(paper "A4")
	(title_block
		(title "baseboard — 13948-1b.1110WZS1818.brd")
		(comment 1 "Honey Badger (Wiwynn) / footprints 102-109 of 2523")
	)
	(layers
		(0 "F.Cu" signal "TOP")
		(4 "In1.Cu" signal "L2GND")
		(6 "In2.Cu" signal "L3")
		(8 "In3.Cu" signal "L4VCC")
		(10 "In4.Cu" signal "L5VCC")
		(12 "In5.Cu" signal "L6")
		(14 "In6.Cu" signal "L7GND")
		(2 "B.Cu" signal "BOTTOM")
		(9 "F.Adhes" user "F.Adhesive")
		(11 "B.Adhes" user "B.Adhesive")
		(13 "F.Paste" user "Package Geometry/Pastemask Top")
		(15 "B.Paste" user "Package Geometry/Pastemask Bottom")
		(5 "F.SilkS" user "Ref Des/Silkscreen Top")
		(7 "B.SilkS" user "Ref Des/Silkscreen Bottom")
		(1 "F.Mask" user "Board Geometry/Soldermask Top")
		(3 "B.Mask" user "Board Geometry/Soldermask Bottom")
		(17 "Dwgs.User" user "User.Drawings")
		(19 "Cmts.User" user "User.Comments")
		(21 "Eco1.User" user "User.Eco1")
		(23 "Eco2.User" user "User.Eco2")
		(25 "Edge.Cuts" user "Board Geometry/Outline")
		(27 "Margin" user)
		(31 "F.CrtYd" user "Package Geometry/Place Bound Top")
		(29 "B.CrtYd" user "Package Geometry/Place Bound Bottom")
		(35 "F.Fab" user "Ref Des/Assembly Top")
		(33 "B.Fab" user "Ref Des/Assembly Bottom")
	)
	(footprint ""
		(layer "F.Cu")
		(at 250.259596 -51.962812 -90)
		(property "Reference" "SR718"
			(at 0 0 270)
			(layer "F.SilkS")
			(hide yes)
			(effects
				(font
					(size 1.27 1.27)
				)
			)
		)
		(property "Value" "0R2J-2-GP"
			(at 0.064008 -3.993896 270)
			(unlocked yes)
			(layer "F.Fab")
			(hide yes)
			(effects
				(font
					(size 1.016 1.016)
					(thickness 0.1524)
				)
			)
		)
		(property "Device Type" "R402H16"
			(at 0.064008 -5.517896 270)
			(unlocked yes)
			(layer "F.Fab")
			(hide yes)
			(effects
				(font
					(size 1.016 1.016)
					(thickness 0.1524)
				)
			)
		)
		(duplicate_pad_numbers_are_jumpers no)
		(fp_line
			(start -0.508 -0.9398)
			(end -0.508 0.9398)
			(stroke
				(width 0.1524)
				(type default)
			)
			(layer "F.SilkS")
		)
		(fp_line
			(start 0.508 -0.9398)
			(end -0.508 -0.9398)
			(stroke
				(width 0.1524)
				(type default)
			)
			(layer "F.SilkS")
		)
		(fp_rect
			(start -0.508 0.9398)
			(end 0.508 -0.9398)
			(stroke
				(width 0)
				(type default)
			)
			(fill no)
			(layer "F.CrtYd")
		)
		(fp_rect
			(start -0.508 0.9398)
			(end 0.508 -0.9398)
			(stroke
				(width 0)
				(type default)
			)
			(fill no)
			(layer "F.Fab")
		)
		(pad "1" smd custom
			(at 0 -0.4445 270)
			(size 0.1397 0.1397)
			(layers "F.Cu" "F.Mask" "F.Paste")
			(net "IOC_EEPROM_WP")
			(options
				(clearance outline)
				(anchor circle)
			)
			(primitives
				(gr_poly
					(pts
						(arc
							(start -0.1778 -0.2794)
							(mid -0.249642 -0.249642)
							(end -0.2794 -0.1778)
						)
						(arc
							(start -0.2794 0.1778)
							(mid -0.249642 0.249642)
							(end -0.1778 0.2794)
						)
						(arc
							(start 0.1778 0.2794)
							(mid 0.249642 0.249642)
							(end 0.2794 0.1778)
						)
						(arc
							(start 0.2794 -0.1778)
							(mid 0.249642 -0.249642)
							(end 0.1778 -0.2794)
						)
					)
					(width 0)
					(fill yes)
				)
			)
		)
		(pad "2" smd custom
			(at 0 0.4445 270)
			(size 0.1397 0.1397)
			(layers "F.Cu" "F.Mask" "F.Paste")
			(net "GND")
			(options
				(clearance outline)
				(anchor circle)
			)
			(primitives
				(gr_poly
					(pts
						(arc
							(start -0.1778 -0.2794)
							(mid -0.249642 -0.249642)
							(end -0.2794 -0.1778)
						)
						(arc
							(start -0.2794 0.1778)
							(mid -0.249642 0.249642)
							(end -0.1778 0.2794)
						)
						(arc
							(start 0.1778 0.2794)
							(mid 0.249642 0.249642)
							(end 0.2794 0.1778)
						)
						(arc
							(start 0.2794 -0.1778)
							(mid 0.249642 -0.249642)
							(end 0.1778 -0.2794)
						)
					)
					(width 0)
					(fill yes)
				)
			)
		)
	)
	(footprint ""
		(layer "F.Cu")
		(at 44.2722 -116.2812 -90)
		(property "Reference" "SR937"
			(at 0 0 270)
			(layer "F.SilkS")
			(hide yes)
			(effects
				(font
					(size 1.27 1.27)
				)
			)
		)
		(property "Value" "0R2J-2-GP"
			(at 0.064008 -3.993896 270)
			(unlocked yes)
			(layer "F.Fab")
			(hide yes)
			(effects
				(font
					(size 1.016 1.016)
					(thickness 0.1524)
				)
			)
		)
		(property "Device Type" "R402H16"
			(at 0.064008 -5.517896 270)
			(unlocked yes)
			(layer "F.Fab")
			(hide yes)
			(effects
				(font
					(size 1.016 1.016)
					(thickness 0.1524)
				)
			)
		)
		(duplicate_pad_numbers_are_jumpers no)
		(fp_line
			(start -0.508 -0.9398)
			(end -0.508 0.9398)
			(stroke
				(width 0.1524)
				(type default)
			)
			(layer "F.SilkS")
		)
		(fp_line
			(start 0.508 -0.9398)
			(end -0.508 -0.9398)
			(stroke
				(width 0.1524)
				(type default)
			)
			(layer "F.SilkS")
		)
		(fp_rect
			(start -0.508 0.9398)
			(end 0.508 -0.9398)
			(stroke
				(width 0)
				(type default)
			)
			(fill no)
			(layer "F.CrtYd")
		)
		(fp_rect
			(start -0.508 0.9398)
			(end 0.508 -0.9398)
			(stroke
				(width 0)
				(type default)
			)
			(fill no)
			(layer "F.Fab")
		)
		(pad "1" smd custom
			(at 0 -0.4445 270)
			(size 0.1397 0.1397)
			(layers "F.Cu" "F.Mask" "F.Paste")
			(net "SAS_SDBRX")
			(options
				(clearance outline)
				(anchor circle)
			)
			(primitives
				(gr_poly
					(pts
						(arc
							(start -0.1778 -0.2794)
							(mid -0.249642 -0.249642)
							(end -0.2794 -0.1778)
						)
						(arc
							(start -0.2794 0.1778)
							(mid -0.249642 0.249642)
							(end -0.1778 0.2794)
						)
						(arc
							(start 0.1778 0.2794)
							(mid 0.249642 0.249642)
							(end 0.2794 0.1778)
						)
						(arc
							(start 0.2794 -0.1778)
							(mid 0.249642 -0.249642)
							(end 0.1778 -0.2794)
						)
					)
					(width 0)
					(fill yes)
				)
			)
		)
		(pad "2" smd custom
			(at 0 0.4445 270)
			(size 0.1397 0.1397)
			(layers "F.Cu" "F.Mask" "F.Paste")
			(net "SAS_R_SDBRX")
			(options
				(clearance outline)
				(anchor circle)
			)
			(primitives
				(gr_poly
					(pts
						(arc
							(start -0.1778 -0.2794)
							(mid -0.249642 -0.249642)
							(end -0.2794 -0.1778)
						)
						(arc
							(start -0.2794 0.1778)
							(mid -0.249642 0.249642)
							(end -0.1778 0.2794)
						)
						(arc
							(start 0.1778 0.2794)
							(mid 0.249642 0.249642)
							(end 0.2794 0.1778)
						)
						(arc
							(start 0.2794 -0.1778)
							(mid 0.249642 -0.249642)
							(end 0.1778 -0.2794)
						)
					)
					(width 0)
					(fill yes)
				)
			)
		)
	)
	(footprint ""
		(layer "F.Cu")
		(at 296.028872 -223.592136 180)
		(property "Reference" "PC85"
			(at 0 0 180)
			(layer "F.SilkS")
			(hide yes)
			(effects
				(font
					(size 1.27 1.27)
				)
			)
		)
		(property "Value" "SC10U6D3V5KX-1GP"
			(at -0.0762 -6.1214 180)
			(unlocked yes)
			(layer "F.Fab")
			(hide yes)
			(effects
				(font
					(size 1.016 1.016)
					(thickness 0.1524)
				)
			)
		)
		(property "Device Type" "C805H54"
			(at -0.0762 -8.1534 180)
			(unlocked yes)
			(layer "F.Fab")
			(hide yes)
			(effects
				(font
					(size 1.016 1.016)
					(thickness 0.1524)
				)
			)
		)
		(duplicate_pad_numbers_are_jumpers no)
		(fp_line
			(start 0.635 0)
			(end -0.635 0)
			(stroke
				(width 0.508)
				(type default)
			)
			(layer "F.SilkS")
		)
		(fp_rect
			(start -0.9652 1.778)
			(end 0.9652 -1.778)
			(stroke
				(width 0)
				(type default)
			)
			(fill no)
			(layer "F.CrtYd")
		)
		(fp_poly
			(pts
				(xy -0.9652 -1.778) (xy 0.9652 -1.778) (xy 0.9652 1.778) (xy -0.9652 1.778)
			)
			(stroke
				(width 0)
				(type default)
			)
			(fill no)
			(layer "F.Fab")
		)
		(pad "1" smd rect
			(at 0 -0.9652 180)
			(size 1.397 1.143)
			(layers "F.Cu" "F.Mask" "F.Paste")
			(net "TPS74801_1V53_STBY_OUT")
		)
		(pad "2" smd rect
			(at 0 0.9652 180)
			(size 1.397 1.143)
			(layers "F.Cu" "F.Mask" "F.Paste")
			(net "GND")
		)
	)
	(footprint ""
		(layer "F.Cu")
		(at 289.687 -65.659 90)
		(property "Reference" "PR9002"
			(at 0 0 90)
			(layer "F.SilkS")
			(hide yes)
			(effects
				(font
					(size 1.27 1.27)
				)
			)
		)
		(property "Value" "0R2J-2-GP"
			(at 0.064008 -3.993896 90)
			(unlocked yes)
			(layer "F.Fab")
			(hide yes)
			(effects
				(font
					(size 1.016 1.016)
					(thickness 0.1524)
				)
			)
		)
		(property "Device Type" "R402H16"
			(at 0.064008 -5.517896 90)
			(unlocked yes)
			(layer "F.Fab")
			(hide yes)
			(effects
				(font
					(size 1.016 1.016)
					(thickness 0.1524)
				)
			)
		)
		(duplicate_pad_numbers_are_jumpers no)
		(fp_line
			(start 0.508 -0.9398)
			(end -0.508 -0.9398)
			(stroke
				(width 0.1524)
				(type default)
			)
			(layer "F.SilkS")
		)
		(fp_line
			(start -0.508 -0.9398)
			(end -0.508 0.9398)
			(stroke
				(width 0.1524)
				(type default)
			)
			(layer "F.SilkS")
		)
		(fp_rect
			(start -0.508 0.9398)
			(end 0.508 -0.9398)
			(stroke
				(width 0)
				(type default)
			)
			(fill no)
			(layer "F.CrtYd")
		)
		(fp_rect
			(start -0.508 0.9398)
			(end 0.508 -0.9398)
			(stroke
				(width 0)
				(type default)
			)
			(fill no)
			(layer "F.Fab")
		)
		(pad "1" smd custom
			(at 0 -0.4445 90)
			(size 0.1397 0.1397)
			(layers "F.Cu" "F.Mask" "F.Paste")
			(net "HSW_SCL1")
			(options
				(clearance outline)
				(anchor circle)
			)
			(primitives
				(gr_poly
					(pts
						(arc
							(start -0.1778 -0.2794)
							(mid -0.249642 -0.249642)
							(end -0.2794 -0.1778)
						)
						(arc
							(start -0.2794 0.1778)
							(mid -0.249642 0.249642)
							(end -0.1778 0.2794)
						)
						(arc
							(start 0.1778 0.2794)
							(mid 0.249642 0.249642)
							(end 0.2794 0.1778)
						)
						(arc
							(start 0.2794 -0.1778)
							(mid 0.249642 -0.249642)
							(end 0.1778 -0.2794)
						)
					)
					(width 0)
					(fill yes)
				)
			)
		)
		(pad "2" smd custom
			(at 0 0.4445 90)
			(size 0.1397 0.1397)
			(layers "F.Cu" "F.Mask" "F.Paste")
			(net "BMC_I2C_SCL_10")
			(options
				(clearance outline)
				(anchor circle)
			)
			(primitives
				(gr_poly
					(pts
						(arc
							(start -0.1778 -0.2794)
							(mid -0.249642 -0.249642)
							(end -0.2794 -0.1778)
						)
						(arc
							(start -0.2794 0.1778)
							(mid -0.249642 0.249642)
							(end -0.1778 0.2794)
						)
						(arc
							(start 0.1778 0.2794)
							(mid 0.249642 0.249642)
							(end 0.2794 0.1778)
						)
						(arc
							(start 0.2794 -0.1778)
							(mid 0.249642 -0.249642)
							(end 0.1778 -0.2794)
						)
					)
					(width 0)
					(fill yes)
				)
			)
		)
	)
	(footprint ""
		(layer "F.Cu")
		(at 30.011116 -81.522062 -90)
		(property "Reference" "R675"
			(at 0 0 270)
			(layer "F.SilkS")
			(hide yes)
			(effects
				(font
					(size 1.27 1.27)
				)
			)
		)
		(property "Value" "1KR2F-3-GP"
			(at 0.064008 -3.993896 270)
			(unlocked yes)
			(layer "F.Fab")
			(hide yes)
			(effects
				(font
					(size 1.016 1.016)
					(thickness 0.1524)
				)
			)
		)
		(property "Device Type" "R402H16"
			(at 0.064008 -5.517896 270)
			(unlocked yes)
			(layer "F.Fab")
			(hide yes)
			(effects
				(font
					(size 1.016 1.016)
					(thickness 0.1524)
				)
			)
		)
		(duplicate_pad_numbers_are_jumpers no)
		(fp_line
			(start -0.508 -0.9398)
			(end -0.508 0.9398)
			(stroke
				(width 0.1524)
				(type default)
			)
			(layer "F.SilkS")
		)
		(fp_line
			(start 0.508 -0.9398)
			(end -0.508 -0.9398)
			(stroke
				(width 0.1524)
				(type default)
			)
			(layer "F.SilkS")
		)
		(fp_rect
			(start -0.508 0.9398)
			(end 0.508 -0.9398)
			(stroke
				(width 0)
				(type default)
			)
			(fill no)
			(layer "F.CrtYd")
		)
		(fp_rect
			(start -0.508 0.9398)
			(end 0.508 -0.9398)
			(stroke
				(width 0)
				(type default)
			)
			(fill no)
			(layer "F.Fab")
		)
		(pad "1" smd custom
			(at 0 -0.4445 270)
			(size 0.1397 0.1397)
			(layers "F.Cu" "F.Mask" "F.Paste")
			(net "INTA_LED_RED_B")
			(options
				(clearance outline)
				(anchor circle)
			)
			(primitives
				(gr_poly
					(pts
						(arc
							(start -0.1778 -0.2794)
							(mid -0.249642 -0.249642)
							(end -0.2794 -0.1778)
						)
						(arc
							(start -0.2794 0.1778)
							(mid -0.249642 0.249642)
							(end -0.1778 0.2794)
						)
						(arc
							(start 0.1778 0.2794)
							(mid 0.249642 0.249642)
							(end 0.2794 0.1778)
						)
						(arc
							(start 0.2794 -0.1778)
							(mid 0.249642 -0.249642)
							(end 0.1778 -0.2794)
						)
					)
					(width 0)
					(fill yes)
				)
			)
		)
		(pad "2" smd custom
			(at 0 0.4445 270)
			(size 0.1397 0.1397)
			(layers "F.Cu" "F.Mask" "F.Paste")
			(net "SAS_ACTIVITY_LED16")
			(options
				(clearance outline)
				(anchor circle)
			)
			(primitives
				(gr_poly
					(pts
						(arc
							(start -0.1778 -0.2794)
							(mid -0.249642 -0.249642)
							(end -0.2794 -0.1778)
						)
						(arc
							(start -0.2794 0.1778)
							(mid -0.249642 0.249642)
							(end -0.1778 0.2794)
						)
						(arc
							(start 0.1778 0.2794)
							(mid 0.249642 0.249642)
							(end 0.2794 0.1778)
						)
						(arc
							(start 0.2794 -0.1778)
							(mid 0.249642 -0.249642)
							(end 0.1778 -0.2794)
						)
					)
					(width 0)
					(fill yes)
				)
			)
		)
	)
	(footprint ""
		(layer "F.Cu")
		(at 92.21597 -96.647 -90)
		(property "Reference" "SR780"
			(at 0 0 270)
			(layer "F.SilkS")
			(hide yes)
			(effects
				(font
					(size 1.27 1.27)
				)
			)
		)
		(property "Value" "4K7R2F-GP"
			(at 0.064008 -3.993896 270)
			(unlocked yes)
			(layer "F.Fab")
			(hide yes)
			(effects
				(font
					(size 1.016 1.016)
					(thickness 0.1524)
				)
			)
		)
		(property "Device Type" "R402H16"
			(at 0.064008 -5.517896 270)
			(unlocked yes)
			(layer "F.Fab")
			(hide yes)
			(effects
				(font
					(size 1.016 1.016)
					(thickness 0.1524)
				)
			)
		)
		(duplicate_pad_numbers_are_jumpers no)
		(fp_line
			(start -0.508 -0.9398)
			(end -0.508 0.9398)
			(stroke
				(width 0.1524)
				(type default)
			)
			(layer "F.SilkS")
		)
		(fp_line
			(start 0.508 -0.9398)
			(end -0.508 -0.9398)
			(stroke
				(width 0.1524)
				(type default)
			)
			(layer "F.SilkS")
		)
		(fp_rect
			(start -0.508 0.9398)
			(end 0.508 -0.9398)
			(stroke
				(width 0)
				(type default)
			)
			(fill no)
			(layer "F.CrtYd")
		)
		(fp_rect
			(start -0.508 0.9398)
			(end 0.508 -0.9398)
			(stroke
				(width 0)
				(type default)
			)
			(fill no)
			(layer "F.Fab")
		)
		(pad "1" smd custom
			(at 0 -0.4445 270)
			(size 0.1397 0.1397)
			(layers "F.Cu" "F.Mask" "F.Paste")
			(net "EXP_XM_ADDR_19")
			(options
				(clearance outline)
				(anchor circle)
			)
			(primitives
				(gr_poly
					(pts
						(arc
							(start -0.1778 -0.2794)
							(mid -0.249642 -0.249642)
							(end -0.2794 -0.1778)
						)
						(arc
							(start -0.2794 0.1778)
							(mid -0.249642 0.249642)
							(end -0.1778 0.2794)
						)
						(arc
							(start 0.1778 0.2794)
							(mid 0.249642 0.249642)
							(end 0.2794 0.1778)
						)
						(arc
							(start 0.2794 -0.1778)
							(mid 0.249642 -0.249642)
							(end 0.1778 -0.2794)
						)
					)
					(width 0)
					(fill yes)
				)
			)
		)
		(pad "2" smd custom
			(at 0 0.4445 270)
			(size 0.1397 0.1397)
			(layers "F.Cu" "F.Mask" "F.Paste")
			(net "GND")
			(options
				(clearance outline)
				(anchor circle)
			)
			(primitives
				(gr_poly
					(pts
						(arc
							(start -0.1778 -0.2794)
							(mid -0.249642 -0.249642)
							(end -0.2794 -0.1778)
						)
						(arc
							(start -0.2794 0.1778)
							(mid -0.249642 0.249642)
							(end -0.1778 0.2794)
						)
						(arc
							(start 0.1778 0.2794)
							(mid 0.249642 0.249642)
							(end 0.2794 0.1778)
						)
						(arc
							(start 0.2794 -0.1778)
							(mid 0.249642 -0.249642)
							(end 0.1778 -0.2794)
						)
					)
					(width 0)
					(fill yes)
				)
			)
		)
	)
	(footprint ""
		(layer "F.Cu")
		(at 203.708 -185.42 180)
		(property "Reference" "R484"
			(at 0 0 180)
			(layer "F.SilkS")
			(hide yes)
			(effects
				(font
					(size 1.27 1.27)
				)
			)
		)
		(property "Value" "1KR2F-3-GP"
			(at 0.064008 -3.993896 180)
			(unlocked yes)
			(layer "F.Fab")
			(hide yes)
			(effects
				(font
					(size 1.016 1.016)
					(thickness 0.1524)
				)
			)
		)
		(property "Device Type" "R402H16"
			(at 0.064008 -5.517896 180)
			(unlocked yes)
			(layer "F.Fab")
			(hide yes)
			(effects
				(font
					(size 1.016 1.016)
					(thickness 0.1524)
				)
			)
		)
		(duplicate_pad_numbers_are_jumpers no)
		(fp_line
			(start 0.508 -0.9398)
			(end -0.508 -0.9398)
			(stroke
				(width 0.1524)
				(type default)
			)
			(layer "F.SilkS")
		)
		(fp_line
			(start -0.508 -0.9398)
			(end -0.508 0.9398)
			(stroke
				(width 0.1524)
				(type default)
			)
			(layer "F.SilkS")
		)
		(fp_rect
			(start -0.508 0.9398)
			(end 0.508 -0.9398)
			(stroke
				(width 0)
				(type default)
			)
			(fill no)
			(layer "F.CrtYd")
		)
		(fp_rect
			(start -0.508 0.9398)
			(end 0.508 -0.9398)
			(stroke
				(width 0)
				(type default)
			)
			(fill no)
			(layer "F.Fab")
		)
		(pad "1" smd custom
			(at 0 -0.4445 180)
			(size 0.1397 0.1397)
			(layers "F.Cu" "F.Mask" "F.Paste")
			(net "P3V3_STBY")
			(options
				(clearance outline)
				(anchor circle)
			)
			(primitives
				(gr_poly
					(pts
						(arc
							(start -0.1778 -0.2794)
							(mid -0.249642 -0.249642)
							(end -0.2794 -0.1778)
						)
						(arc
							(start -0.2794 0.1778)
							(mid -0.249642 0.249642)
							(end -0.1778 0.2794)
						)
						(arc
							(start 0.1778 0.2794)
							(mid 0.249642 0.249642)
							(end 0.2794 0.1778)
						)
						(arc
							(start 0.2794 -0.1778)
							(mid 0.249642 -0.249642)
							(end 0.1778 -0.2794)
						)
					)
					(width 0)
					(fill yes)
				)
			)
		)
		(pad "2" smd custom
			(at 0 0.4445 180)
			(size 0.1397 0.1397)
			(layers "F.Cu" "F.Mask" "F.Paste")
			(net "DIVIDER 1_IN")
			(options
				(clearance outline)
				(anchor circle)
			)
			(primitives
				(gr_poly
					(pts
						(arc
							(start -0.1778 -0.2794)
							(mid -0.249642 -0.249642)
							(end -0.2794 -0.1778)
						)
						(arc
							(start -0.2794 0.1778)
							(mid -0.249642 0.249642)
							(end -0.1778 0.2794)
						)
						(arc
							(start 0.1778 0.2794)
							(mid 0.249642 0.249642)
							(end 0.2794 0.1778)
						)
						(arc
							(start 0.2794 -0.1778)
							(mid 0.249642 -0.249642)
							(end 0.1778 -0.2794)
						)
					)
					(width 0)
					(fill yes)
				)
			)
		)
	)
	(footprint ""
		(layer "F.Cu")
		(at 43.561 -230.759)
		(property "Reference" "C303"
			(at 0 0 0)
			(layer "F.SilkS")
			(hide yes)
			(effects
				(font
					(size 1.27 1.27)
				)
			)
		)
		(property "Value" "SCD1U25V2KX-2-GP"
			(at 1.1811 -2.7051 0)
			(unlocked yes)
			(layer "F.Fab")
			(hide yes)
			(effects
				(font
					(size 1.016 1.016)
					(thickness 0.1524)
				)
			)
		)
		(property "Device Type" "C402H22"
			(at 1.1811 -4.2291 0)
			(unlocked yes)
			(layer "F.Fab")
			(hide yes)
			(effects
				(font
					(size 1.016 1.016)
					(thickness 0.1524)
				)
			)
		)
		(duplicate_pad_numbers_are_jumpers no)
		(fp_rect
			(start -0.4318 0.9525)
			(end 0.4318 -0.9525)
			(stroke
				(width 0)
				(type default)
			)
			(fill no)
			(layer "F.CrtYd")
		)
		(fp_rect
			(start -0.4318 0.9525)
			(end 0.4318 -0.9525)
			(stroke
				(width 0)
				(type default)
			)
			(fill no)
			(layer "F.Fab")
		)
		(pad "1" smd custom
			(at 0 -0.4445)
			(size 0.1524 0.1524)
			(layers "F.Cu" "F.Mask" "F.Paste")
			(net "P12V_PCIE")
			(options
				(clearance outline)
				(anchor circle)
			)
			(primitives
				(gr_poly
					(pts
						(arc
							(start 0.3048 -0.2032)
							(mid 0.275042 -0.275042)
							(end 0.2032 -0.3048)
						)
						(arc
							(start -0.2032 -0.3048)
							(mid -0.275042 -0.275042)
							(end -0.3048 -0.2032)
						)
						(arc
							(start -0.3048 0.2032)
							(mid -0.275042 0.275042)
							(end -0.2032 0.3048)
						)
						(arc
							(start 0.2032 0.3048)
							(mid 0.275042 0.275042)
							(end 0.3048 0.2032)
						)
					)
					(width 0)
					(fill yes)
				)
			)
		)
		(pad "2" smd custom
			(at 0 0.4445)
			(size 0.1524 0.1524)
			(layers "F.Cu" "F.Mask" "F.Paste")
			(net "GND")
			(options
				(clearance outline)
				(anchor circle)
			)
			(primitives
				(gr_poly
					(pts
						(arc
							(start 0.3048 -0.2032)
							(mid 0.275042 -0.275042)
							(end 0.2032 -0.3048)
						)
						(arc
							(start -0.2032 -0.3048)
							(mid -0.275042 -0.275042)
							(end -0.3048 -0.2032)
						)
						(arc
							(start -0.3048 0.2032)
							(mid -0.275042 0.275042)
							(end -0.2032 0.3048)
						)
						(arc
							(start 0.2032 0.3048)
							(mid 0.275042 0.275042)
							(end 0.3048 0.2032)
						)
					)
					(width 0)
					(fill yes)
				)
			)
		)
	)
)
